(kicad_pcb
	(version 20260206)
	(generator "pcbnew")
	(generator_version "10.0")
	(general
		(thickness 1.6)
		(legacy_teardrops no)
	)
	(paper "A4")
	(title_block
		(title "03242023_DA0F0TMBIJ0_F0T_Motherboard_J_brd_V01_OCP.brd")
		(comment 1 "Grand Teton / footprints 5492-5497 of 6105")
	)
	(layers
		(0 "F.Cu" signal "TOP")
		(4 "In1.Cu" signal "GND")
		(6 "In2.Cu" signal "IN1")
		(8 "In3.Cu" signal "GND1")
		(10 "In4.Cu" signal "IN2")
		(12 "In5.Cu" signal "GND2")
		(14 "In6.Cu" signal "IN3")
		(16 "In7.Cu" signal "GND3")
		(18 "In8.Cu" signal "VCC")
		(20 "In9.Cu" signal "VCC1")
		(22 "In10.Cu" signal "GND4")
		(24 "In11.Cu" signal "IN4")
		(26 "In12.Cu" signal "GND5")
		(28 "In13.Cu" signal "IN5")
		(30 "In14.Cu" signal "GND6")
		(32 "In15.Cu" signal "IN6")
		(34 "In16.Cu" signal "GND7")
		(2 "B.Cu" signal "BOTTOM")
		(9 "F.Adhes" user "F.Adhesive")
		(11 "B.Adhes" user "B.Adhesive")
		(13 "F.Paste" user "Package Geometry/Pastemask Top")
		(15 "B.Paste" user "Package Geometry/Pastemask Bottom")
		(5 "F.SilkS" user "Ref Des/Silkscreen Top")
		(7 "B.SilkS" user "Ref Des/Silkscreen Bottom")
		(1 "F.Mask" user "Board Geometry/Soldermask Top")
		(3 "B.Mask" user "Board Geometry/Soldermask Bottom")
		(17 "Dwgs.User" user "User.Drawings")
		(19 "Cmts.User" user "User.Comments")
		(21 "Eco1.User" user "User.Eco1")
		(23 "Eco2.User" user "User.Eco2")
		(25 "Edge.Cuts" user "Board Geometry/Outline")
		(27 "Margin" user)
		(31 "F.CrtYd" user "Package Geometry/Place Bound Top")
		(29 "B.CrtYd" user "Package Geometry/Place Bound Bottom")
		(35 "F.Fab" user "Ref Des/Assembly Top")
		(33 "B.Fab" user "Ref Des/Assembly Bottom")
	)
	(footprint ""
		(layer "B.Cu")
		(at 63.104268 -195.810378 -90)
		(property "Reference" "R4299"
			(at 0 0 90)
			(layer "B.SilkS")
			(hide yes)
			(effects
				(font
					(size 1.27 1.27)
				)
				(justify mirror)
			)
		)
		(property "Value" ""
			(at 0 0 90)
			(layer "B.Fab")
			(effects
				(font
					(size 1.27 1.27)
				)
				(justify mirror)
			)
		)
		(duplicate_pad_numbers_are_jumpers no)
		(fp_line
			(start -0.7874 0.4064)
			(end 0.7874 0.4064)
			(stroke
				(width 0.1524)
				(type default)
			)
			(layer "B.SilkS")
		)
		(fp_line
			(start 0.7874 0.4064)
			(end 0.7874 -0.4064)
			(stroke
				(width 0.1524)
				(type default)
			)
			(layer "B.SilkS")
		)
		(fp_line
			(start -0.7874 -0.4064)
			(end -0.7874 0.4064)
			(stroke
				(width 0.1524)
				(type default)
			)
			(layer "B.SilkS")
		)
		(fp_line
			(start 0.7874 -0.4064)
			(end -0.7874 -0.4064)
			(stroke
				(width 0.1524)
				(type default)
			)
			(layer "B.SilkS")
		)
		(fp_line
			(start -0.67945 0.3048)
			(end -0.120396 0.3048)
			(stroke
				(width 0.1)
				(type default)
			)
			(layer "B.Fab")
		)
		(fp_line
			(start -0.120396 0.3048)
			(end -0.120396 0.2794)
			(stroke
				(width 0.1)
				(type default)
			)
			(layer "B.Fab")
		)
		(fp_line
			(start 0.12065 0.3048)
			(end 0.67945 0.3048)
			(stroke
				(width 0.1)
				(type default)
			)
			(layer "B.Fab")
		)
		(fp_line
			(start 0.67945 0.3048)
			(end 0.67945 -0.305054)
			(stroke
				(width 0.1)
				(type default)
			)
			(layer "B.Fab")
		)
		(fp_line
			(start -0.120396 0.2794)
			(end 0.12065 0.2794)
			(stroke
				(width 0.1)
				(type default)
			)
			(layer "B.Fab")
		)
		(fp_line
			(start 0.12065 0.2794)
			(end 0.12065 0.3048)
			(stroke
				(width 0.1)
				(type default)
			)
			(layer "B.Fab")
		)
		(fp_line
			(start -0.12065 -0.2794)
			(end -0.12065 -0.3048)
			(stroke
				(width 0.1)
				(type default)
			)
			(layer "B.Fab")
		)
		(fp_line
			(start 0.12065 -0.2794)
			(end -0.12065 -0.2794)
			(stroke
				(width 0.1)
				(type default)
			)
			(layer "B.Fab")
		)
		(fp_line
			(start -0.67945 -0.3048)
			(end -0.67945 0.3048)
			(stroke
				(width 0.1)
				(type default)
			)
			(layer "B.Fab")
		)
		(fp_line
			(start -0.12065 -0.3048)
			(end -0.67945 -0.3048)
			(stroke
				(width 0.1)
				(type default)
			)
			(layer "B.Fab")
		)
		(fp_line
			(start 0.12065 -0.305054)
			(end 0.12065 -0.2794)
			(stroke
				(width 0.1)
				(type default)
			)
			(layer "B.Fab")
		)
		(fp_line
			(start 0.67945 -0.305054)
			(end 0.12065 -0.305054)
			(stroke
				(width 0.1)
				(type default)
			)
			(layer "B.Fab")
		)
		(pad "1" smd circle
			(at 0.40005 0 90)
			(size 0 0)
			(layers "B.Cu" "B.Mask" "B.Paste")
			(net "PWRGD_DRAMPWRGD_CPU1_AB_LVC1_R2")
		)
		(pad "2" smd circle
			(at -0.40005 0 90)
			(size 0 0)
			(layers "B.Cu" "B.Mask" "B.Paste")
			(net "PWRGD_DRAMPWRGD_CPU1_AB_LVC1_R")
		)
	)
	(footprint ""
		(layer "B.Cu")
		(at 334.931258 -58.465466 -90)
		(property "Reference" "C1197"
			(at 0 0 90)
			(layer "B.SilkS")
			(hide yes)
			(effects
				(font
					(size 1.27 1.27)
				)
				(justify mirror)
			)
		)
		(property "Value" ""
			(at 0 0 90)
			(layer "B.Fab")
			(effects
				(font
					(size 1.27 1.27)
				)
				(justify mirror)
			)
		)
		(duplicate_pad_numbers_are_jumpers no)
		(fp_line
			(start -1.2954 0.5842)
			(end 1.2954 0.5842)
			(stroke
				(width 0.1524)
				(type default)
			)
			(layer "B.SilkS")
		)
		(fp_line
			(start 1.2954 0.5842)
			(end 1.2954 -0.5842)
			(stroke
				(width 0.1524)
				(type default)
			)
			(layer "B.SilkS")
		)
		(fp_line
			(start -1.2954 -0.5842)
			(end -1.2954 0.5842)
			(stroke
				(width 0.1524)
				(type default)
			)
			(layer "B.SilkS")
		)
		(fp_line
			(start 0 -0.5842)
			(end 0 0.5842)
			(stroke
				(width 0.1524)
				(type default)
			)
			(layer "B.SilkS")
		)
		(fp_line
			(start 1.2954 -0.5842)
			(end -1.2954 -0.5842)
			(stroke
				(width 0.1524)
				(type default)
			)
			(layer "B.SilkS")
		)
		(fp_line
			(start -0.8636 0.4572)
			(end 0.8636 0.4572)
			(stroke
				(width 0.1)
				(type default)
			)
			(layer "B.Fab")
		)
		(fp_line
			(start 0.8636 0.4572)
			(end 0.8636 0.4064)
			(stroke
				(width 0.1)
				(type default)
			)
			(layer "B.Fab")
		)
		(fp_line
			(start -1.1938 0.4064)
			(end -0.8636 0.4064)
			(stroke
				(width 0.1)
				(type default)
			)
			(layer "B.Fab")
		)
		(fp_line
			(start -0.8636 0.4064)
			(end -0.8636 0.4572)
			(stroke
				(width 0.1)
				(type default)
			)
			(layer "B.Fab")
		)
		(fp_line
			(start 0.8636 0.4064)
			(end 1.1938 0.4064)
			(stroke
				(width 0.1)
				(type default)
			)
			(layer "B.Fab")
		)
		(fp_line
			(start 1.1938 0.4064)
			(end 1.1938 -0.4064)
			(stroke
				(width 0.1)
				(type default)
			)
			(layer "B.Fab")
		)
		(fp_line
			(start -1.1938 -0.4064)
			(end -1.1938 0.4064)
			(stroke
				(width 0.1)
				(type default)
			)
			(layer "B.Fab")
		)
		(fp_line
			(start -0.8636 -0.4064)
			(end -1.1938 -0.4064)
			(stroke
				(width 0.1)
				(type default)
			)
			(layer "B.Fab")
		)
		(fp_line
			(start 0.8636 -0.4064)
			(end 0.8636 -0.4572)
			(stroke
				(width 0.1)
				(type default)
			)
			(layer "B.Fab")
		)
		(fp_line
			(start 1.1938 -0.4064)
			(end 0.8636 -0.4064)
			(stroke
				(width 0.1)
				(type default)
			)
			(layer "B.Fab")
		)
		(fp_line
			(start -0.8636 -0.4572)
			(end -0.8636 -0.4064)
			(stroke
				(width 0.1)
				(type default)
			)
			(layer "B.Fab")
		)
		(fp_line
			(start 0.8636 -0.4572)
			(end -0.8636 -0.4572)
			(stroke
				(width 0.1)
				(type default)
			)
			(layer "B.Fab")
		)
		(pad "1" smd rect
			(at 0.7366 0 180)
			(size 0.7112 0.8128)
			(layers "B.Cu" "B.Mask" "B.Paste")
			(net "P1V8_PCH_AUX")
		)
		(pad "2" smd rect
			(at -0.7366 0 180)
			(size 0.7112 0.8128)
			(layers "B.Cu" "B.Mask" "B.Paste")
			(net "GND")
		)
	)
	(footprint ""
		(layer "B.Cu")
		(at 434.209444 -180.971698 -90)
		(property "Reference" "R1652"
			(at 0 0 90)
			(layer "B.SilkS")
			(hide yes)
			(effects
				(font
					(size 1.27 1.27)
				)
				(justify mirror)
			)
		)
		(property "Value" ""
			(at 0 0 90)
			(layer "B.Fab")
			(effects
				(font
					(size 1.27 1.27)
				)
				(justify mirror)
			)
		)
		(duplicate_pad_numbers_are_jumpers no)
		(fp_line
			(start -0.7874 0.4064)
			(end 0.7874 0.4064)
			(stroke
				(width 0.1524)
				(type default)
			)
			(layer "B.SilkS")
		)
		(fp_line
			(start 0.7874 0.4064)
			(end 0.7874 -0.4064)
			(stroke
				(width 0.1524)
				(type default)
			)
			(layer "B.SilkS")
		)
		(fp_line
			(start -0.7874 -0.4064)
			(end -0.7874 0.4064)
			(stroke
				(width 0.1524)
				(type default)
			)
			(layer "B.SilkS")
		)
		(fp_line
			(start 0.7874 -0.4064)
			(end -0.7874 -0.4064)
			(stroke
				(width 0.1524)
				(type default)
			)
			(layer "B.SilkS")
		)
		(fp_line
			(start -0.67945 0.3048)
			(end -0.120396 0.3048)
			(stroke
				(width 0.1)
				(type default)
			)
			(layer "B.Fab")
		)
		(fp_line
			(start -0.120396 0.3048)
			(end -0.120396 0.2794)
			(stroke
				(width 0.1)
				(type default)
			)
			(layer "B.Fab")
		)
		(fp_line
			(start 0.12065 0.3048)
			(end 0.67945 0.3048)
			(stroke
				(width 0.1)
				(type default)
			)
			(layer "B.Fab")
		)
		(fp_line
			(start 0.67945 0.3048)
			(end 0.67945 -0.305054)
			(stroke
				(width 0.1)
				(type default)
			)
			(layer "B.Fab")
		)
		(fp_line
			(start -0.120396 0.2794)
			(end 0.12065 0.2794)
			(stroke
				(width 0.1)
				(type default)
			)
			(layer "B.Fab")
		)
		(fp_line
			(start 0.12065 0.2794)
			(end 0.12065 0.3048)
			(stroke
				(width 0.1)
				(type default)
			)
			(layer "B.Fab")
		)
		(fp_line
			(start -0.12065 -0.2794)
			(end -0.12065 -0.3048)
			(stroke
				(width 0.1)
				(type default)
			)
			(layer "B.Fab")
		)
		(fp_line
			(start 0.12065 -0.2794)
			(end -0.12065 -0.2794)
			(stroke
				(width 0.1)
				(type default)
			)
			(layer "B.Fab")
		)
		(fp_line
			(start -0.67945 -0.3048)
			(end -0.67945 0.3048)
			(stroke
				(width 0.1)
				(type default)
			)
			(layer "B.Fab")
		)
		(fp_line
			(start -0.12065 -0.3048)
			(end -0.67945 -0.3048)
			(stroke
				(width 0.1)
				(type default)
			)
			(layer "B.Fab")
		)
		(fp_line
			(start 0.12065 -0.305054)
			(end 0.12065 -0.2794)
			(stroke
				(width 0.1)
				(type default)
			)
			(layer "B.Fab")
		)
		(fp_line
			(start 0.67945 -0.305054)
			(end 0.12065 -0.305054)
			(stroke
				(width 0.1)
				(type default)
			)
			(layer "B.Fab")
		)
		(pad "1" smd circle
			(at 0.40005 0 90)
			(size 0 0)
			(layers "B.Cu" "B.Mask" "B.Paste")
			(net "PWRGD_PVNN_MAIN_CPU0_R")
		)
		(pad "2" smd circle
			(at -0.40005 0 90)
			(size 0 0)
			(layers "B.Cu" "B.Mask" "B.Paste")
			(net "PWRGD_PVNN_MAIN_CPU0")
		)
	)
	(footprint ""
		(layer "B.Cu")
		(at 408.124152 -193.08953 -90)
		(property "Reference" "R279"
			(at 0 0 90)
			(layer "B.SilkS")
			(hide yes)
			(effects
				(font
					(size 1.27 1.27)
				)
				(justify mirror)
			)
		)
		(property "Value" ""
			(at 0 0 90)
			(layer "B.Fab")
			(effects
				(font
					(size 1.27 1.27)
				)
				(justify mirror)
			)
		)
		(duplicate_pad_numbers_are_jumpers no)
		(fp_line
			(start -0.7874 0.4064)
			(end 0.7874 0.4064)
			(stroke
				(width 0.1524)
				(type default)
			)
			(layer "B.SilkS")
		)
		(fp_line
			(start 0.7874 0.4064)
			(end 0.7874 -0.4064)
			(stroke
				(width 0.1524)
				(type default)
			)
			(layer "B.SilkS")
		)
		(fp_line
			(start -0.7874 -0.4064)
			(end -0.7874 0.4064)
			(stroke
				(width 0.1524)
				(type default)
			)
			(layer "B.SilkS")
		)
		(fp_line
			(start 0.7874 -0.4064)
			(end -0.7874 -0.4064)
			(stroke
				(width 0.1524)
				(type default)
			)
			(layer "B.SilkS")
		)
		(fp_line
			(start -0.67945 0.3048)
			(end -0.120396 0.3048)
			(stroke
				(width 0.1)
				(type default)
			)
			(layer "B.Fab")
		)
		(fp_line
			(start -0.120396 0.3048)
			(end -0.120396 0.2794)
			(stroke
				(width 0.1)
				(type default)
			)
			(layer "B.Fab")
		)
		(fp_line
			(start 0.12065 0.3048)
			(end 0.67945 0.3048)
			(stroke
				(width 0.1)
				(type default)
			)
			(layer "B.Fab")
		)
		(fp_line
			(start 0.67945 0.3048)
			(end 0.67945 -0.305054)
			(stroke
				(width 0.1)
				(type default)
			)
			(layer "B.Fab")
		)
		(fp_line
			(start -0.120396 0.2794)
			(end 0.12065 0.2794)
			(stroke
				(width 0.1)
				(type default)
			)
			(layer "B.Fab")
		)
		(fp_line
			(start 0.12065 0.2794)
			(end 0.12065 0.3048)
			(stroke
				(width 0.1)
				(type default)
			)
			(layer "B.Fab")
		)
		(fp_line
			(start -0.12065 -0.2794)
			(end -0.12065 -0.3048)
			(stroke
				(width 0.1)
				(type default)
			)
			(layer "B.Fab")
		)
		(fp_line
			(start 0.12065 -0.2794)
			(end -0.12065 -0.2794)
			(stroke
				(width 0.1)
				(type default)
			)
			(layer "B.Fab")
		)
		(fp_line
			(start -0.67945 -0.3048)
			(end -0.67945 0.3048)
			(stroke
				(width 0.1)
				(type default)
			)
			(layer "B.Fab")
		)
		(fp_line
			(start -0.12065 -0.3048)
			(end -0.67945 -0.3048)
			(stroke
				(width 0.1)
				(type default)
			)
			(layer "B.Fab")
		)
		(fp_line
			(start 0.12065 -0.305054)
			(end 0.12065 -0.2794)
			(stroke
				(width 0.1)
				(type default)
			)
			(layer "B.Fab")
		)
		(fp_line
			(start 0.67945 -0.305054)
			(end 0.12065 -0.305054)
			(stroke
				(width 0.1)
				(type default)
			)
			(layer "B.Fab")
		)
		(pad "1" smd circle
			(at 0.40005 0 90)
			(size 0 0)
			(layers "B.Cu" "B.Mask" "B.Paste")
			(net "PVNN_TERM_CPU0")
		)
		(pad "2" smd circle
			(at -0.40005 0 90)
			(size 0 0)
			(layers "B.Cu" "B.Mask" "B.Paste")
			(net "PU_CPU0_SOCKET_ID0")
		)
	)
	(footprint ""
		(layer "B.Cu")
		(at 416.080956 -318.730376)
		(property "Reference" "R34"
			(at 0 0 0)
			(layer "B.SilkS")
			(hide yes)
			(effects
				(font
					(size 1.27 1.27)
				)
				(justify mirror)
			)
		)
		(property "Value" ""
			(at 0 0 0)
			(layer "B.Fab")
			(effects
				(font
					(size 1.27 1.27)
				)
				(justify mirror)
			)
		)
		(duplicate_pad_numbers_are_jumpers no)
		(fp_line
			(start -0.7874 -0.4064)
			(end -0.7874 0.4064)
			(stroke
				(width 0.1524)
				(type default)
			)
			(layer "B.SilkS")
		)
		(fp_line
			(start -0.7874 0.4064)
			(end 0.7874 0.4064)
			(stroke
				(width 0.1524)
				(type default)
			)
			(layer "B.SilkS")
		)
		(fp_line
			(start 0.7874 -0.4064)
			(end -0.7874 -0.4064)
			(stroke
				(width 0.1524)
				(type default)
			)
			(layer "B.SilkS")
		)
		(fp_line
			(start 0.7874 0.4064)
			(end 0.7874 -0.4064)
			(stroke
				(width 0.1524)
				(type default)
			)
			(layer "B.SilkS")
		)
		(fp_line
			(start -0.67945 -0.3048)
			(end -0.67945 0.3048)
			(stroke
				(width 0.1)
				(type default)
			)
			(layer "B.Fab")
		)
		(fp_line
			(start -0.67945 0.3048)
			(end -0.120396 0.3048)
			(stroke
				(width 0.1)
				(type default)
			)
			(layer "B.Fab")
		)
		(fp_line
			(start -0.12065 -0.3048)
			(end -0.67945 -0.3048)
			(stroke
				(width 0.1)
				(type default)
			)
			(layer "B.Fab")
		)
		(fp_line
			(start -0.12065 -0.2794)
			(end -0.12065 -0.3048)
			(stroke
				(width 0.1)
				(type default)
			)
			(layer "B.Fab")
		)
		(fp_line
			(start -0.120396 0.2794)
			(end 0.12065 0.2794)
			(stroke
				(width 0.1)
				(type default)
			)
			(layer "B.Fab")
		)
		(fp_line
			(start -0.120396 0.3048)
			(end -0.120396 0.2794)
			(stroke
				(width 0.1)
				(type default)
			)
			(layer "B.Fab")
		)
		(fp_line
			(start 0.12065 -0.305054)
			(end 0.12065 -0.2794)
			(stroke
				(width 0.1)
				(type default)
			)
			(layer "B.Fab")
		)
		(fp_line
			(start 0.12065 -0.2794)
			(end -0.12065 -0.2794)
			(stroke
				(width 0.1)
				(type default)
			)
			(layer "B.Fab")
		)
		(fp_line
			(start 0.12065 0.2794)
			(end 0.12065 0.3048)
			(stroke
				(width 0.1)
				(type default)
			)
			(layer "B.Fab")
		)
		(fp_line
			(start 0.12065 0.3048)
			(end 0.67945 0.3048)
			(stroke
				(width 0.1)
				(type default)
			)
			(layer "B.Fab")
		)
		(fp_line
			(start 0.67945 -0.305054)
			(end 0.12065 -0.305054)
			(stroke
				(width 0.1)
				(type default)
			)
			(layer "B.Fab")
		)
		(fp_line
			(start 0.67945 0.3048)
			(end 0.67945 -0.305054)
			(stroke
				(width 0.1)
				(type default)
			)
			(layer "B.Fab")
		)
		(pad "1" smd circle
			(at 0.40005 0 180)
			(size 0 0)
			(layers "B.Cu" "B.Mask" "B.Paste")
			(net "PD_CHE_CPU0_DIMM1_SAA")
		)
		(pad "2" smd circle
			(at -0.40005 0 180)
			(size 0 0)
			(layers "B.Cu" "B.Mask" "B.Paste")
			(net "GND")
		)
	)
	(footprint ""
		(layer "B.Cu")
		(at 435.05628 -44.14012 90)
		(property "Reference" "R4682"
			(at 0 0 90)
			(layer "B.SilkS")
			(hide yes)
			(effects
				(font
					(size 1.27 1.27)
				)
				(justify mirror)
			)
		)
		(property "Value" ""
			(at 0 0 90)
			(layer "B.Fab")
			(effects
				(font
					(size 1.27 1.27)
				)
				(justify mirror)
			)
		)
		(duplicate_pad_numbers_are_jumpers no)
		(fp_line
			(start 0.7874 -0.4064)
			(end -0.7874 -0.4064)
			(stroke
				(width 0.1524)
				(type default)
			)
			(layer "B.SilkS")
		)
		(fp_line
			(start -0.7874 -0.4064)
			(end -0.7874 0.4064)
			(stroke
				(width 0.1524)
				(type default)
			)
			(layer "B.SilkS")
		)
		(fp_line
			(start 0.7874 0.4064)
			(end 0.7874 -0.4064)
			(stroke
				(width 0.1524)
				(type default)
			)
			(layer "B.SilkS")
		)
		(fp_line
			(start -0.7874 0.4064)
			(end 0.7874 0.4064)
			(stroke
				(width 0.1524)
				(type default)
			)
			(layer "B.SilkS")
		)
		(fp_line
			(start 0.67945 -0.305054)
			(end 0.12065 -0.305054)
			(stroke
				(width 0.1)
				(type default)
			)
			(layer "B.Fab")
		)
		(fp_line
			(start 0.12065 -0.305054)
			(end 0.12065 -0.2794)
			(stroke
				(width 0.1)
				(type default)
			)
			(layer "B.Fab")
		)
		(fp_line
			(start -0.12065 -0.3048)
			(end -0.67945 -0.3048)
			(stroke
				(width 0.1)
				(type default)
			)
			(layer "B.Fab")
		)
		(fp_line
			(start -0.67945 -0.3048)
			(end -0.67945 0.3048)
			(stroke
				(width 0.1)
				(type default)
			)
			(layer "B.Fab")
		)
		(fp_line
			(start 0.12065 -0.2794)
			(end -0.12065 -0.2794)
			(stroke
				(width 0.1)
				(type default)
			)
			(layer "B.Fab")
		)
		(fp_line
			(start -0.12065 -0.2794)
			(end -0.12065 -0.3048)
			(stroke
				(width 0.1)
				(type default)
			)
			(layer "B.Fab")
		)
		(fp_line
			(start 0.12065 0.2794)
			(end 0.12065 0.3048)
			(stroke
				(width 0.1)
				(type default)
			)
			(layer "B.Fab")
		)
		(fp_line
			(start -0.120396 0.2794)
			(end 0.12065 0.2794)
			(stroke
				(width 0.1)
				(type default)
			)
			(layer "B.Fab")
		)
		(fp_line
			(start 0.67945 0.3048)
			(end 0.67945 -0.305054)
			(stroke
				(width 0.1)
				(type default)
			)
			(layer "B.Fab")
		)
		(fp_line
			(start 0.12065 0.3048)
			(end 0.67945 0.3048)
			(stroke
				(width 0.1)
				(type default)
			)
			(layer "B.Fab")
		)
		(fp_line
			(start -0.120396 0.3048)
			(end -0.120396 0.2794)
			(stroke
				(width 0.1)
				(type default)
			)
			(layer "B.Fab")
		)
		(fp_line
			(start -0.67945 0.3048)
			(end -0.120396 0.3048)
			(stroke
				(width 0.1)
				(type default)
			)
			(layer "B.Fab")
		)
		(pad "1" smd circle
			(at 0.40005 0 270)
			(size 0 0)
			(layers "B.Cu" "B.Mask" "B.Paste")
			(net "PWRGD_P5V")
		)
		(pad "2" smd circle
			(at -0.40005 0 270)
			(size 0 0)
			(layers "B.Cu" "B.Mask" "B.Paste")
			(net "GND")
		)
	)
)
